(kicad_pcb
	(version 20241229)
	(generator "pcbnew")
	(generator_version "9.0")
	(general
		(thickness 1.6)
		(legacy_teardrops no)
	)
	(paper "A4")
	(title_block
		(title "environment-sensor")
		(comment 1 "footprints 47-52 of 109")
	)
	(layers
		(0 "F.Cu" signal)
		(4 "In1.Cu" signal)
		(6 "In2.Cu" signal)
		(2 "B.Cu" signal)
		(9 "F.Adhes" user "F.Adhesive")
		(11 "B.Adhes" user "B.Adhesive")
		(13 "F.Paste" user)
		(15 "B.Paste" user)
		(5 "F.SilkS" user "F.Silkscreen")
		(7 "B.SilkS" user "B.Silkscreen")
		(1 "F.Mask" user)
		(3 "B.Mask" user)
		(17 "Dwgs.User" user "User.Drawings")
		(19 "Cmts.User" user "User.Comments")
		(21 "Eco1.User" user "User.Eco1")
		(23 "Eco2.User" user "User.Eco2")
		(25 "Edge.Cuts" user)
		(27 "Margin" user)
		(31 "F.CrtYd" user "F.Courtyard")
		(29 "B.CrtYd" user "B.Courtyard")
		(35 "F.Fab" user)
		(33 "B.Fab" user)
	)
	(footprint "antmicro-footprints:SOT-723"
		(layer "F.Cu")
		(at 202.35 128.25)
		(property "Reference" "D6"
			(at 0.35 -1.25 180)
			(layer "F.SilkS")
			(effects
				(font
					(size 0.65 0.65)
					(thickness 0.15)
				)
			)
		)
		(property "Value" "TPD2E009_SOT-9X3"
			(at -0.025 2.975 0)
			(layer "F.Fab")
			(effects
				(font
					(size 1 1)
					(thickness 0.15)
				)
			)
		)
		(property "Description" "TVS diode array, 8 kV, SOT-723, 5.5 V, 0.9 pF"
			(at 0 0 0)
			(layer "F.Fab")
			(hide yes)
			(effects
				(font
					(size 1.27 1.27)
					(thickness 0.15)
				)
			)
		)
		(property "Author" "Antmicro"
			(at 0 0 0)
			(layer "F.Fab")
			(hide yes)
			(effects
				(font
					(size 1 1)
					(thickness 0.15)
				)
			)
		)
		(property "License" "Apache-2.0"
			(at 0 0 0)
			(layer "F.Fab")
			(hide yes)
			(effects
				(font
					(size 1 1)
					(thickness 0.15)
				)
			)
		)
		(property "MPN" "TPD2E009DRTR"
			(at 0 0 0)
			(layer "F.Fab")
			(hide yes)
			(effects
				(font
					(size 1 1)
					(thickness 0.15)
				)
			)
		)
		(property "Manufacturer" "Texas Instruments"
			(at 0 0 0)
			(layer "F.Fab")
			(hide yes)
			(effects
				(font
					(size 1 1)
					(thickness 0.15)
				)
			)
		)
		(sheetfile "environment-sensor.kicad_sch")
		(attr smd)
		(fp_line
			(start -0.43 -0.1375)
			(end -0.43 0.1375)
			(stroke
				(width 0.15)
				(type solid)
			)
			(layer "F.SilkS")
		)
		(fp_line
			(start 0.43 -0.63)
			(end -0.2175 -0.63)
			(stroke
				(width 0.15)
				(type solid)
			)
			(layer "F.SilkS")
		)
		(fp_line
			(start 0.43 -0.23)
			(end 0.43 -0.63)
			(stroke
				(width 0.15)
				(type solid)
			)
			(layer "F.SilkS")
		)
		(fp_line
			(start 0.43 0.23)
			(end 0.43 0.63)
			(stroke
				(width 0.15)
				(type solid)
			)
			(layer "F.SilkS")
		)
		(fp_line
			(start 0.43 0.63)
			(end -0.22 0.63)
			(stroke
				(width 0.15)
				(type solid)
			)
			(layer "F.SilkS")
		)
		(fp_rect
			(start -0.83 -0.83)
			(end 0.83 0.83)
			(stroke
				(width 0.05)
				(type solid)
			)
			(fill no)
			(layer "F.CrtYd")
		)
		(fp_line
			(start -0.09 -0.53)
			(end -0.43 -0.19)
			(stroke
				(width 0.15)
				(type solid)
			)
			(layer "F.Fab")
		)
		(fp_line
			(start 0.424 -0.528)
			(end 0.424 0.524)
			(stroke
				(width 0.15)
				(type solid)
			)
			(layer "F.Fab")
		)
		(fp_line
			(start 0.424 0.524)
			(end -0.424 0.524)
			(stroke
				(width 0.15)
				(type solid)
			)
			(layer "F.Fab")
		)
		(fp_rect
			(start 0.424 0.524)
			(end -0.43 -0.528)
			(stroke
				(width 0.15)
				(type solid)
			)
			(fill no)
			(layer "F.Fab")
		)
		(fp_text user "${REFERENCE}"
			(at 0 0 0)
			(layer "F.Fab")
			(effects
				(font
					(size 0.2 0.2)
					(thickness 0.025)
				)
			)
		)
		(pad "1" smd rect
			(at -0.501 -0.401 270)
			(size 0.3 0.4)
			(layers "F.Cu" "F.Mask" "F.Paste")
			(net 8 "I2C_1_SCL")
			(pinfunction "1")
			(pintype "passive")
		)
		(pad "2" smd rect
			(at -0.501 0.399 270)
			(size 0.3 0.4)
			(layers "F.Cu" "F.Mask" "F.Paste")
			(net 9 "I2C_1_SDA")
			(pinfunction "2")
			(pintype "passive")
		)
		(pad "3" smd rect
			(at 0.499 -0.001 270)
			(size 0.3 0.4)
			(layers "F.Cu" "F.Mask" "F.Paste")
			(net 1 "GND")
			(pinfunction "3")
			(pintype "passive")
		)
	)
	(footprint "antmicro-footprints:C_0402_1005Metric"
		(layer "F.Cu")
		(at 192.95 138.4 90)
		(descr "Capacitor SMD 0402")
		(tags "capacitor SMD 0402")
		(property "Reference" "C19"
			(at 17.924 -9.0695 90)
			(layer "B.SilkS")
			(effects
				(font
					(size 0.7 0.7)
					(thickness 0.15)
				)
				(justify left bottom mirror)
			)
		)
		(property "Value" "C_100n_0402"
			(at 0 1.4 90)
			(layer "F.Fab")
			(effects
				(font
					(size 0.7 0.7)
					(thickness 0.15)
				)
				(justify left bottom)
			)
		)
		(property "Description" "SMD Multilayer Ceramic Capacitor, 0.1 µF, 50 V, 0402 [1005 Metric], ± 10%, X5R, GRM Series"
			(at 0 0 90)
			(layer "F.Fab")
			(hide yes)
			(effects
				(font
					(size 1.27 1.27)
					(thickness 0.15)
				)
			)
		)
		(property "Author" "Antmicro"
			(at 331.35 -54.55 0)
			(layer "F.Fab")
			(hide yes)
			(effects
				(font
					(size 1 1)
					(thickness 0.15)
				)
			)
		)
		(property "Dielectric" "X5R"
			(at 331.35 -54.55 0)
			(layer "F.Fab")
			(hide yes)
			(effects
				(font
					(size 1 1)
					(thickness 0.15)
				)
			)
		)
		(property "License" "Apache-2.0"
			(at 331.35 -54.55 0)
			(layer "F.Fab")
			(hide yes)
			(effects
				(font
					(size 1 1)
					(thickness 0.15)
				)
			)
		)
		(property "MPN" "GRM155R61H104KE14D"
			(at 331.35 -54.55 0)
			(layer "F.Fab")
			(hide yes)
			(effects
				(font
					(size 1 1)
					(thickness 0.15)
				)
			)
		)
		(property "Manufacturer" "Murata"
			(at 331.35 -54.55 0)
			(layer "F.Fab")
			(hide yes)
			(effects
				(font
					(size 1 1)
					(thickness 0.15)
				)
			)
		)
		(property "Public" "False"
			(at 331.35 -54.55 0)
			(layer "F.Fab")
			(hide yes)
			(effects
				(font
					(size 1 1)
					(thickness 0.15)
				)
			)
		)
		(property "Val" "100n"
			(at 331.35 -54.55 0)
			(layer "F.Fab")
			(hide yes)
			(effects
				(font
					(size 1 1)
					(thickness 0.15)
				)
			)
		)
		(property "Voltage" "50V"
			(at 331.35 -54.55 0)
			(layer "F.Fab")
			(hide yes)
			(effects
				(font
					(size 1 1)
					(thickness 0.15)
				)
			)
		)
		(sheetfile "environment-sensor.kicad_sch")
		(attr smd)
		(fp_rect
			(start -0.925 -0.47)
			(end 0.925 0.47)
			(stroke
				(width 0.05)
				(type default)
			)
			(fill no)
			(layer "F.CrtYd")
		)
		(fp_line
			(start 0.504 -0.25)
			(end 0.504 0.248)
			(stroke
				(width 0.15)
				(type solid)
			)
			(layer "F.Fab")
		)
		(fp_line
			(start -0.494 -0.25)
			(end 0.504 -0.25)
			(stroke
				(width 0.15)
				(type solid)
			)
			(layer "F.Fab")
		)
		(fp_line
			(start 0.504 0.248)
			(end -0.494 0.248)
			(stroke
				(width 0.15)
				(type solid)
			)
			(layer "F.Fab")
		)
		(fp_line
			(start -0.494 0.248)
			(end -0.494 -0.25)
			(stroke
				(width 0.15)
				(type solid)
			)
			(layer "F.Fab")
		)
		(pad "1" smd roundrect
			(at -0.48 0 90)
			(size 0.59 0.64)
			(layers "F.Cu" "F.Mask" "F.Paste")
			(roundrect_rratio 0.25)
			(net 30 "Net-(U3-VDDA)")
			(pintype "passive")
		)
		(pad "2" smd roundrect
			(at 0.48 0 90)
			(size 0.59 0.64)
			(layers "F.Cu" "F.Mask" "F.Paste")
			(roundrect_rratio 0.25)
			(net 1 "GND")
			(pintype "passive")
		)
	)
	(footprint "antmicro-footprints:TP_SMD_1mm"
		(layer "F.Cu")
		(at 198.761 136.042 -90)
		(property "Reference" "TP7"
			(at 0.258 -0.439 270)
			(layer "F.SilkS")
			(hide yes)
			(effects
				(font
					(size 0.7 0.7)
					(thickness 0.15)
				)
				(justify left bottom)
			)
		)
		(property "Value" "TP_1mm_SMD"
			(at 0 1.4 270)
			(layer "F.Fab")
			(effects
				(font
					(size 0.7 0.7)
					(thickness 0.15)
				)
				(justify left bottom)
			)
		)
		(property "Description" "Test point 1mm SMD"
			(at 0 0 270)
			(layer "F.Fab")
			(hide yes)
			(effects
				(font
					(size 1.27 1.27)
					(thickness 0.15)
				)
			)
		)
		(property "Author" "Antmicro"
			(at 62.719 334.803 0)
			(layer "F.Fab")
			(hide yes)
			(effects
				(font
					(size 1 1)
					(thickness 0.15)
				)
			)
		)
		(property "License" "Apache-2.0"
			(at 62.719 334.803 0)
			(layer "F.Fab")
			(hide yes)
			(effects
				(font
					(size 1 1)
					(thickness 0.15)
				)
			)
		)
		(property "MPN" ""
			(at 62.719 334.803 0)
			(layer "F.Fab")
			(hide yes)
			(effects
				(font
					(size 1 1)
					(thickness 0.15)
				)
			)
		)
		(property "Manufacturer" ""
			(at 62.719 334.803 0)
			(layer "F.Fab")
			(hide yes)
			(effects
				(font
					(size 1 1)
					(thickness 0.15)
				)
			)
		)
		(property "Public" "False"
			(at 62.719 334.803 0)
			(layer "F.Fab")
			(hide yes)
			(effects
				(font
					(size 1 1)
					(thickness 0.15)
				)
			)
		)
		(sheetfile "environment-sensor.kicad_sch")
		(attr exclude_from_pos_files)
		(pad "1" smd circle
			(at 0 0 270)
			(size 1 1)
			(layers "F.Cu" "F.Mask")
			(net 15 "/FRAM_WP")
			(pinfunction "1")
			(pintype "passive")
		)
	)
	(footprint "antmicro-footprints:Resonator_SMD_Abracon_ABM3B_5x3.2mm"
		(layer "F.Cu")
		(at 179.81 136.35 180)
		(descr "Abracon's CERAMIC SMD CRYSTAL")
		(tags "smd ceramic xtal")
		(property "Reference" "Y2"
			(at 0.21 3.15 0)
			(layer "F.SilkS")
			(effects
				(font
					(size 0.7 0.7)
					(thickness 0.15)
				)
				(justify right bottom)
			)
		)
		(property "Value" "Resonator_8MHz_ABM3B"
			(at 0 4.2 0)
			(layer "F.Fab")
			(effects
				(font
					(size 0.7 0.7)
					(thickness 0.15)
				)
				(justify right bottom)
			)
		)
		(property "Description" "Crystal, 8 MHz, SMT, 5mm x 3.2mm, 10 ppm, 10 pF, 10 ppm"
			(at 0 0 180)
			(layer "F.Fab")
			(hide yes)
			(effects
				(font
					(size 1.27 1.27)
					(thickness 0.15)
				)
			)
		)
		(property "Author" "Antmicro"
			(at 359.62 272.7 0)
			(layer "F.Fab")
			(hide yes)
			(effects
				(font
					(size 1 1)
					(thickness 0.15)
				)
			)
		)
		(property "License" "Apache-2.0"
			(at 359.62 272.7 0)
			(layer "F.Fab")
			(hide yes)
			(effects
				(font
					(size 1 1)
					(thickness 0.15)
				)
			)
		)
		(property "MPN" "ABM3B-8.000MHZ-10-1-U-T"
			(at 359.62 272.7 0)
			(layer "F.Fab")
			(hide yes)
			(effects
				(font
					(size 1 1)
					(thickness 0.15)
				)
			)
		)
		(property "Manufacturer" "Abracon"
			(at 359.62 272.7 0)
			(layer "F.Fab")
			(hide yes)
			(effects
				(font
					(size 1 1)
					(thickness 0.15)
				)
			)
		)
		(property "Public" "False"
			(at 359.62 272.7 0)
			(layer "F.Fab")
			(hide yes)
			(effects
				(font
					(size 1 1)
					(thickness 0.15)
				)
			)
		)
		(property "Val" "8 MHz"
			(at 359.62 272.7 0)
			(layer "F.Fab")
			(hide yes)
			(effects
				(font
					(size 1 1)
					(thickness 0.15)
				)
			)
		)
		(sheetfile "environment-sensor.kicad_sch")
		(attr smd)
		(fp_line
			(start 1.6 -0.783)
			(end 1.6 0.78)
			(stroke
				(width 0.15)
				(type solid)
			)
			(layer "F.SilkS")
		)
		(fp_line
			(start -0.282 2.499)
			(end 0.281 2.499)
			(stroke
				(width 0.15)
				(type solid)
			)
			(layer "F.SilkS")
		)
		(fp_line
			(start -0.282 -2.5)
			(end 0.281 -2.5)
			(stroke
				(width 0.15)
				(type solid)
			)
			(layer "F.SilkS")
		)
		(fp_line
			(start -1.601 -0.783)
			(end -1.601 0.78)
			(stroke
				(width 0.15)
				(type solid)
			)
			(layer "F.SilkS")
		)
		(fp_circle
			(center -1.8 -0.95)
			(end -1.75 -0.95)
			(stroke
				(width 0.15)
				(type solid)
			)
			(fill yes)
			(layer "F.SilkS")
		)
		(fp_rect
			(start -2.089 -3.175)
			(end 2.086 3.175)
			(stroke
				(width 0.05)
				(type solid)
			)
			(fill no)
			(layer "F.CrtYd")
		)
		(fp_line
			(start 1.6 2.499)
			(end -1.599 2.499)
			(stroke
				(width 0.15)
				(type solid)
			)
			(layer "F.Fab")
		)
		(fp_line
			(start 1.6 -2.5)
			(end 1.6 2.499)
			(stroke
				(width 0.15)
				(type solid)
			)
			(layer "F.Fab")
		)
		(fp_line
			(start -0.999 -2.5)
			(end 1.6 -2.5)
			(stroke
				(width 0.15)
				(type solid)
			)
			(layer "F.Fab")
		)
		(fp_line
			(start -1.599 2.499)
			(end -1.599 -1.901)
			(stroke
				(width 0.15)
				(type solid)
			)
			(layer "F.Fab")
		)
		(fp_line
			(start -1.599 -1.901)
			(end -0.999 -2.5)
			(stroke
				(width 0.15)
				(type solid)
			)
			(layer "F.Fab")
		)
		(pad "1" smd rect
			(at -1.2 -2 180)
			(size 1.2 1.8)
			(layers "F.Cu" "F.Mask" "F.Paste")
			(net 31 "Net-(U3-PF1-OSC_OUT)")
			(pintype "passive")
		)
		(pad "2" smd rect
			(at -1.2 1.999 180)
			(size 1.2 1.8)
			(layers "F.Cu" "F.Mask" "F.Paste")
			(net 1 "GND")
			(pinfunction "SH")
			(pintype "passive")
		)
		(pad "3" smd rect
			(at 1.199 1.999 180)
			(size 1.2 1.8)
			(layers "F.Cu" "F.Mask" "F.Paste")
			(net 33 "Net-(U3-PF0-OSC_IN)")
			(pintype "passive")
		)
		(pad "4" smd rect
			(at 1.199 -2 180)
			(size 1.2 1.8)
			(layers "F.Cu" "F.Mask" "F.Paste")
			(net 1 "GND")
			(pinfunction "SH")
			(pintype "passive")
		)
	)
	(footprint "antmicro-footprints:C_0402_1005Metric"
		(layer "F.Cu")
		(at 185.994 125.087 90)
		(descr "Capacitor SMD 0402")
		(tags "capacitor SMD 0402")
		(property "Reference" "C9"
			(at 7.838 9.132 0)
			(layer "F.SilkS")
			(effects
				(font
					(size 0.7 0.7)
					(thickness 0.15)
				)
				(justify left bottom)
			)
		)
		(property "Value" "C_4u7_0402"
			(at 0 1.4 90)
			(layer "F.Fab")
			(effects
				(font
					(size 0.7 0.7)
					(thickness 0.15)
				)
				(justify left bottom)
			)
		)
		(property "Description" "SMD Multilayer Ceramic Capacitor, 4.7 µF, 10 V, 0402 [1005 Metric], ± 20%, X5R, GRM Series"
			(at 0 0 90)
			(layer "F.Fab")
			(hide yes)
			(effects
				(font
					(size 1.27 1.27)
					(thickness 0.15)
				)
			)
		)
		(property "Author" "Antmicro"
			(at 311.081 -60.907 0)
			(layer "F.Fab")
			(hide yes)
			(effects
				(font
					(size 1 1)
					(thickness 0.15)
				)
			)
		)
		(property "Dielectric" ""
			(at 311.081 -60.907 0)
			(layer "F.Fab")
			(hide yes)
			(effects
				(font
					(size 1 1)
					(thickness 0.15)
				)
			)
		)
		(property "License" "Apache-2.0"
			(at 311.081 -60.907 0)
			(layer "F.Fab")
			(hide yes)
			(effects
				(font
					(size 1 1)
					(thickness 0.15)
				)
			)
		)
		(property "MPN" "GRM155R61A475MEAAD"
			(at 311.081 -60.907 0)
			(layer "F.Fab")
			(hide yes)
			(effects
				(font
					(size 1 1)
					(thickness 0.15)
				)
			)
		)
		(property "Manufacturer" "Murata"
			(at 311.081 -60.907 0)
			(layer "F.Fab")
			(hide yes)
			(effects
				(font
					(size 1 1)
					(thickness 0.15)
				)
			)
		)
		(property "Public" "False"
			(at 311.081 -60.907 0)
			(layer "F.Fab")
			(hide yes)
			(effects
				(font
					(size 1 1)
					(thickness 0.15)
				)
			)
		)
		(property "Val" "4u7"
			(at 311.081 -60.907 0)
			(layer "F.Fab")
			(hide yes)
			(effects
				(font
					(size 1 1)
					(thickness 0.15)
				)
			)
		)
		(property "Voltage" ""
			(at 311.081 -60.907 0)
			(layer "F.Fab")
			(hide yes)
			(effects
				(font
					(size 1 1)
					(thickness 0.15)
				)
			)
		)
		(sheetfile "environment-sensor.kicad_sch")
		(attr smd)
		(fp_rect
			(start -0.925 -0.47)
			(end 0.925 0.47)
			(stroke
				(width 0.05)
				(type default)
			)
			(fill no)
			(layer "F.CrtYd")
		)
		(fp_line
			(start 0.504 -0.25)
			(end 0.504 0.248)
			(stroke
				(width 0.15)
				(type solid)
			)
			(layer "F.Fab")
		)
		(fp_line
			(start -0.494 -0.25)
			(end 0.504 -0.25)
			(stroke
				(width 0.15)
				(type solid)
			)
			(layer "F.Fab")
		)
		(fp_line
			(start 0.504 0.248)
			(end -0.494 0.248)
			(stroke
				(width 0.15)
				(type solid)
			)
			(layer "F.Fab")
		)
		(fp_line
			(start -0.494 0.248)
			(end -0.494 -0.25)
			(stroke
				(width 0.15)
				(type solid)
			)
			(layer "F.Fab")
		)
		(pad "1" smd roundrect
			(at -0.48 0 90)
			(size 0.59 0.64)
			(layers "F.Cu" "F.Mask" "F.Paste")
			(roundrect_rratio 0.25)
			(net 1 "GND")
			(pintype "passive")
		)
		(pad "2" smd roundrect
			(at 0.48 0 90)
			(size 0.59 0.64)
			(layers "F.Cu" "F.Mask" "F.Paste")
			(roundrect_rratio 0.25)
			(net 2 "+3V3")
			(pintype "passive")
		)
	)
	(footprint "antmicro-footprints:R_0402_1005Metric"
		(layer "F.Cu")
		(at 182.925 134.8 180)
		(descr "Resistor SMD 0402")
		(tags "resistor SMD 0402")
		(property "Reference" "R25"
			(at -3.125 -0.4 0)
			(layer "F.SilkS")
			(effects
				(font
					(size 0.7 0.7)
					(thickness 0.15)
				)
				(justify right bottom)
			)
		)
		(property "Value" "R_1M_0402"
			(at -1.011843 1.772047 0)
			(layer "F.Fab")
			(effects
				(font
					(size 0.7 0.7)
					(thickness 0.15)
				)
				(justify right bottom)
			)
		)
		(property "Description" "SMD Chip Resistor, 1 Mohm, ± 1%, 62.5 mW, 0402 [1005 Metric], Thick Film, General Purpose"
			(at 0 0 180)
			(layer "F.Fab")
			(hide yes)
			(effects
				(font
					(size 1.27 1.27)
					(thickness 0.15)
				)
			)
		)
		(property "Author" "Antmicro"
			(at 365.85 269.6 0)
			(layer "F.Fab")
			(hide yes)
			(effects
				(font
					(size 1 1)
					(thickness 0.15)
				)
			)
		)
		(property "License" "Apache-2.0"
			(at 365.85 269.6 0)
			(layer "F.Fab")
			(hide yes)
			(effects
				(font
					(size 1 1)
					(thickness 0.15)
				)
			)
		)
		(property "MPN" "CR0402-FX-1004GLF"
			(at 365.85 269.6 0)
			(layer "F.Fab")
			(hide yes)
			(effects
				(font
					(size 1 1)
					(thickness 0.15)
				)
			)
		)
		(property "Manufacturer" "Bourns"
			(at 365.85 269.6 0)
			(layer "F.Fab")
			(hide yes)
			(effects
				(font
					(size 1 1)
					(thickness 0.15)
				)
			)
		)
		(property "Public" "False"
			(at 365.85 269.6 0)
			(layer "F.Fab")
			(hide yes)
			(effects
				(font
					(size 1 1)
					(thickness 0.15)
				)
			)
		)
		(property "Tolerance" "1%"
			(at 365.85 269.6 0)
			(layer "F.Fab")
			(hide yes)
			(effects
				(font
					(size 1 1)
					(thickness 0.15)
				)
			)
		)
		(property "Val" "1M"
			(at 365.85 269.6 0)
			(layer "F.Fab")
			(hide yes)
			(effects
				(font
					(size 1 1)
					(thickness 0.15)
				)
			)
		)
		(sheetfile "environment-sensor.kicad_sch")
		(attr smd exclude_from_pos_files exclude_from_bom dnp)
		(fp_rect
			(start -0.925 -0.47)
			(end 0.925 0.47)
			(stroke
				(width 0.05)
				(type default)
			)
			(fill no)
			(layer "F.CrtYd")
		)
		(fp_rect
			(start -0.5 -0.25)
			(end 0.5 0.25)
			(stroke
				(width 0.15)
				(type solid)
			)
			(fill no)
			(layer "F.Fab")
		)
		(pad "1" smd roundrect
			(at -0.48 0 180)
			(size 0.59 0.64)
			(layers "F.Cu" "F.Mask" "F.Paste")
			(roundrect_rratio 0.25)
			(net 31 "Net-(U3-PF1-OSC_OUT)")
			(pintype "passive")
		)
		(pad "2" smd roundrect
			(at 0.48 0 180)
			(size 0.59 0.64)
			(layers "F.Cu" "F.Mask" "F.Paste")
			(roundrect_rratio 0.25)
			(net 33 "Net-(U3-PF0-OSC_IN)")
			(pintype "passive")
		)
	)
)
